# T6G (Grand Teton) — schematic netlist excerpt (pin names and nets, part order shuffled) for the footprints in the layout excerpt that follows; sources: Cadence DE-HDL packaged netlist, KiCad conversion of 04192023_DAF0TMB3IC0_F0TG_MB_C_brd_V02_OCP.brd

C6695  Q_CAP_DIFFBUS  DIFF BUS_0.22UF 6.3V 20% X6S  pkg C0201  page 341 : \1\ = P5E_CPU1_P2_TX_BUF_C_DP<1> ; \2\ = P5E_CPU1_P2_TX_BUF_DP<1>
C1067  Q_CAP  0.1UF 10V 10% X7S  pkg C0201  page 186 : A = P3V3_AUX ; B = GND
R6795  Q_RES  200 1% CHIP  pkg 0201LF  page 343 : A = RT_CPU1_P2_VQPS ; B = GND
R1130  Q_RES  0 5% EMPTY  pkg 0402LF  page 136 : A = P12V_OCP_SFF_EN_R ; B = P12V_OCP_SFF_EN_R3
R6822  Q_RES  1K 1% CHIP  pkg 0201LF  page 278 : A = U11_E2 ; B = GND

(kicad_pcb
	(version 20260206)
	(generator "pcbnew")
	(generator_version "10.0")
	(general
		(thickness 1.6)
		(legacy_teardrops no)
	)
	(paper "A4")
	(title_block
		(title "04192023_DAF0TMB3IC0_F0TG_MB_C_brd_V02_OCP.brd")
		(comment 1 "Grand Teton / footprints 1501-1505 of 8354")
	)
	(layers
		(0 "F.Cu" signal "TOP")
		(4 "In1.Cu" signal "GND")
		(6 "In2.Cu" signal "IN1")
		(8 "In3.Cu" signal "GND1")
		(10 "In4.Cu" signal "IN2")
		(12 "In5.Cu" signal "GND2")
		(14 "In6.Cu" signal "IN3")
		(16 "In7.Cu" signal "GND3")
		(18 "In8.Cu" signal "VCC")
		(20 "In9.Cu" signal "VCC1")
		(22 "In10.Cu" signal "GND4")
		(24 "In11.Cu" signal "IN4")
		(26 "In12.Cu" signal "GND5")
		(28 "In13.Cu" signal "IN5")
		(30 "In14.Cu" signal "GND6")
		(32 "In15.Cu" signal "IN6")
		(34 "In16.Cu" signal "GND7")
		(2 "B.Cu" signal "BOTTOM")
		(9 "F.Adhes" user "F.Adhesive")
		(11 "B.Adhes" user "B.Adhesive")
		(13 "F.Paste" user "Package Geometry/Pastemask Top")
		(15 "B.Paste" user "Package Geometry/Pastemask Bottom")
		(5 "F.SilkS" user "Ref Des/Silkscreen Top")
		(7 "B.SilkS" user "Ref Des/Silkscreen Bottom")
		(1 "F.Mask" user "Board Geometry/Soldermask Top")
		(3 "B.Mask" user "Board Geometry/Soldermask Bottom")
		(17 "Dwgs.User" user "User.Drawings")
		(19 "Cmts.User" user "User.Comments")
		(21 "Eco1.User" user "User.Eco1")
		(23 "Eco2.User" user "User.Eco2")
		(25 "Edge.Cuts" user "Board Geometry/Outline")
		(27 "Margin" user)
		(31 "F.CrtYd" user "Package Geometry/Place Bound Top")
		(29 "B.CrtYd" user "Package Geometry/Place Bound Bottom")
		(35 "F.Fab" user "Ref Des/Assembly Top")
		(33 "B.Fab" user "Ref Des/Assembly Bottom")
	)
	(footprint ""
		(layer "F.Cu")
		(at 301.161704 -430.28362 90)
		(property "Reference" "R6822"
			(at 0 0 90)
			(layer "F.SilkS")
			(hide yes)
			(effects
				(font
					(size 1.27 1.27)
				)
			)
		)
		(property "Value" ""
			(at 0 0 90)
			(layer "F.Fab")
			(effects
				(font
					(size 1.27 1.27)
				)
			)
		)
		(duplicate_pad_numbers_are_jumpers no)
		(fp_line
			(start 0.32512 -0.175006)
			(end 0.32512 0.175006)
			(stroke
				(width 0.1)
				(type default)
			)
			(layer "F.Fab")
		)
		(fp_line
			(start -0.32512 -0.175006)
			(end 0.32512 -0.175006)
			(stroke
				(width 0.1)
				(type default)
			)
			(layer "F.Fab")
		)
		(fp_line
			(start 0.32512 0.175006)
			(end -0.32512 0.175006)
			(stroke
				(width 0.1)
				(type default)
			)
			(layer "F.Fab")
		)
		(fp_line
			(start -0.32512 0.175006)
			(end -0.32512 -0.175006)
			(stroke
				(width 0.1)
				(type default)
			)
			(layer "F.Fab")
		)
		(pad "1" smd rect
			(at -0.2667 0 90)
			(size 0.3048 0.381)
			(layers "F.Cu" "F.Mask" "F.Paste")
			(net "U11_E2")
		)
		(pad "2" smd rect
			(at 0.2667 0 270)
			(size 0.3048 0.381)
			(layers "F.Cu" "F.Mask" "F.Paste")
			(net "GND")
		)
	)
	(footprint ""
		(layer "F.Cu")
		(at 118.846346 -408.517344 -90)
		(property "Reference" "C6695"
			(at 0 0 270)
			(layer "F.SilkS")
			(hide yes)
			(effects
				(font
					(size 1.27 1.27)
				)
			)
		)
		(property "Value" ""
			(at 0 0 270)
			(layer "F.Fab")
			(effects
				(font
					(size 1.27 1.27)
				)
			)
		)
		(duplicate_pad_numbers_are_jumpers no)
		(fp_line
			(start -0.299974 0.150114)
			(end -0.299974 -0.150114)
			(stroke
				(width 0.1)
				(type default)
			)
			(layer "F.Fab")
		)
		(fp_line
			(start 0.299974 0.150114)
			(end -0.299974 0.150114)
			(stroke
				(width 0.1)
				(type default)
			)
			(layer "F.Fab")
		)
		(fp_line
			(start -0.299974 -0.150114)
			(end 0.299974 -0.150114)
			(stroke
				(width 0.1)
				(type default)
			)
			(layer "F.Fab")
		)
		(fp_line
			(start 0.299974 -0.150114)
			(end 0.299974 0.150114)
			(stroke
				(width 0.1)
				(type default)
			)
			(layer "F.Fab")
		)
		(pad "1" smd rect
			(at -0.2667 0 270)
			(size 0.3048 0.381)
			(layers "F.Cu" "F.Mask" "F.Paste")
			(net "P5E_CPU1_P2_TX_BUF_C_DP<1>")
		)
		(pad "2" smd rect
			(at 0.2667 0 270)
			(size 0.3048 0.381)
			(layers "F.Cu" "F.Mask" "F.Paste")
			(net "P5E_CPU1_P2_TX_BUF_DP<1>")
		)
	)
	(footprint ""
		(layer "F.Cu")
		(at 114.490246 -399.327116 -90)
		(property "Reference" "C1067"
			(at 0 0 270)
			(layer "F.SilkS")
			(hide yes)
			(effects
				(font
					(size 1.27 1.27)
				)
			)
		)
		(property "Value" ""
			(at 0 0 270)
			(layer "F.Fab")
			(effects
				(font
					(size 1.27 1.27)
				)
			)
		)
		(duplicate_pad_numbers_are_jumpers no)
		(fp_line
			(start -0.299974 0.150114)
			(end -0.299974 -0.150114)
			(stroke
				(width 0.1)
				(type default)
			)
			(layer "F.Fab")
		)
		(fp_line
			(start 0.299974 0.150114)
			(end -0.299974 0.150114)
			(stroke
				(width 0.1)
				(type default)
			)
			(layer "F.Fab")
		)
		(fp_line
			(start -0.299974 -0.150114)
			(end 0.299974 -0.150114)
			(stroke
				(width 0.1)
				(type default)
			)
			(layer "F.Fab")
		)
		(fp_line
			(start 0.299974 -0.150114)
			(end 0.299974 0.150114)
			(stroke
				(width 0.1)
				(type default)
			)
			(layer "F.Fab")
		)
		(pad "1" smd rect
			(at -0.2667 0 270)
			(size 0.3048 0.381)
			(layers "F.Cu" "F.Mask" "F.Paste")
			(net "P3V3_AUX")
		)
		(pad "2" smd rect
			(at 0.2667 0 270)
			(size 0.3048 0.381)
			(layers "F.Cu" "F.Mask" "F.Paste")
			(net "GND")
		)
	)
	(footprint ""
		(layer "F.Cu")
		(at 166.18077 -394.3604 -90)
		(property "Reference" "R6795"
			(at 0 0 270)
			(layer "F.SilkS")
			(hide yes)
			(effects
				(font
					(size 1.27 1.27)
				)
			)
		)
		(property "Value" ""
			(at 0 0 270)
			(layer "F.Fab")
			(effects
				(font
					(size 1.27 1.27)
				)
			)
		)
		(duplicate_pad_numbers_are_jumpers no)
		(fp_line
			(start -0.32512 0.175006)
			(end -0.32512 -0.175006)
			(stroke
				(width 0.1)
				(type default)
			)
			(layer "F.Fab")
		)
		(fp_line
			(start 0.32512 0.175006)
			(end -0.32512 0.175006)
			(stroke
				(width 0.1)
				(type default)
			)
			(layer "F.Fab")
		)
		(fp_line
			(start -0.32512 -0.175006)
			(end 0.32512 -0.175006)
			(stroke
				(width 0.1)
				(type default)
			)
			(layer "F.Fab")
		)
		(fp_line
			(start 0.32512 -0.175006)
			(end 0.32512 0.175006)
			(stroke
				(width 0.1)
				(type default)
			)
			(layer "F.Fab")
		)
		(pad "1" smd rect
			(at -0.2667 0 270)
			(size 0.3048 0.381)
			(layers "F.Cu" "F.Mask" "F.Paste")
			(net "RT_CPU1_P2_VQPS")
		)
		(pad "2" smd rect
			(at 0.2667 0 90)
			(size 0.3048 0.381)
			(layers "F.Cu" "F.Mask" "F.Paste")
			(net "GND")
		)
	)
	(footprint ""
		(layer "F.Cu")
		(at 156.690314 -108.432854 180)
		(property "Reference" "R1130"
			(at 0 0 180)
			(layer "F.SilkS")
			(hide yes)
			(effects
				(font
					(size 1.27 1.27)
				)
			)
		)
		(property "Value" ""
			(at 0 0 180)
			(layer "F.Fab")
			(effects
				(font
					(size 1.27 1.27)
				)
			)
		)
		(duplicate_pad_numbers_are_jumpers no)
		(fp_line
			(start 0.7874 0.4064)
			(end -0.7874 0.4064)
			(stroke
				(width 0.1524)
				(type default)
			)
			(layer "F.SilkS")
		)
		(fp_line
			(start 0.7874 -0.4064)
			(end 0.7874 0.4064)
			(stroke
				(width 0.1524)
				(type default)
			)
			(layer "F.SilkS")
		)
		(fp_line
			(start -0.7874 0.4064)
			(end -0.7874 -0.4064)
			(stroke
				(width 0.1524)
				(type default)
			)
			(layer "F.SilkS")
		)
		(fp_line
			(start -0.7874 -0.4064)
			(end 0.7874 -0.4064)
			(stroke
				(width 0.1524)
				(type default)
			)
			(layer "F.SilkS")
		)
		(fp_line
			(start 0.67945 0.3048)
			(end 0.120396 0.3048)
			(stroke
				(width 0.1)
				(type default)
			)
			(layer "F.Fab")
		)
		(fp_line
			(start 0.67945 -0.3048)
			(end 0.67945 0.3048)
			(stroke
				(width 0.1)
				(type default)
			)
			(layer "F.Fab")
		)
		(fp_line
			(start 0.12065 -0.2794)
			(end 0.12065 -0.3048)
			(stroke
				(width 0.1)
				(type default)
			)
			(layer "F.Fab")
		)
		(fp_line
			(start 0.12065 -0.3048)
			(end 0.67945 -0.3048)
			(stroke
				(width 0.1)
				(type default)
			)
			(layer "F.Fab")
		)
		(fp_line
			(start 0.120396 0.3048)
			(end 0.120396 0.2794)
			(stroke
				(width 0.1)
				(type default)
			)
			(layer "F.Fab")
		)
		(fp_line
			(start 0.120396 0.2794)
			(end -0.12065 0.2794)
			(stroke
				(width 0.1)
				(type default)
			)
			(layer "F.Fab")
		)
		(fp_line
			(start -0.12065 0.3048)
			(end -0.67945 0.3048)
			(stroke
				(width 0.1)
				(type default)
			)
			(layer "F.Fab")
		)
		(fp_line
			(start -0.12065 0.2794)
			(end -0.12065 0.3048)
			(stroke
				(width 0.1)
				(type default)
			)
			(layer "F.Fab")
		)
		(fp_line
			(start -0.12065 -0.2794)
			(end 0.12065 -0.2794)
			(stroke
				(width 0.1)
				(type default)
			)
			(layer "F.Fab")
		)
		(fp_line
			(start -0.12065 -0.305054)
			(end -0.12065 -0.2794)
			(stroke
				(width 0.1)
				(type default)
			)
			(layer "F.Fab")
		)
		(fp_line
			(start -0.67945 0.3048)
			(end -0.67945 -0.305054)
			(stroke
				(width 0.1)
				(type default)
			)
			(layer "F.Fab")
		)
		(fp_line
			(start -0.67945 -0.305054)
			(end -0.12065 -0.305054)
			(stroke
				(width 0.1)
				(type default)
			)
			(layer "F.Fab")
		)
		(pad "1" smd circle
			(at -0.40005 0 180)
			(size 0 0)
			(layers "F.Cu" "F.Mask" "F.Paste")
			(net "P12V_OCP_SFF_EN_R")
		)
		(pad "2" smd circle
			(at 0.40005 0 180)
			(size 0 0)
			(layers "F.Cu" "F.Mask" "F.Paste")
			(net "P12V_OCP_SFF_EN_R3")
		)
	)
)
